# S9S_MB_2U (Grand Teton) — schematic netlist excerpt (pin names and nets, part order shuffled) for the footprints in the layout excerpt that follows; sources: Cadence DE-HDL packaged netlist, KiCad conversion of 03242023_DA0F0TMBIJ0_F0T_Motherboard_J_brd_V01_OCP.brd

Q81  MOSFET_NCH_DUAL  PJT138K IC  pkg SOT363XD  page 253
  S1  = GND
  G1  = PWRGD_PVCCINFAON_CPU0
  D2  = LED_PWRGD_PVNN_MAIN_CPU0_D
  S2  = GND
  G2  = PWRGD_PVNN_MAIN_CPU0
  D1  = LED_PWRGD_PVCCINFAON_CPU0_D

C1570  Q_CAP_DIFFBUS  DIFF BUS_0.22UF 6.3V 20% X6S  pkg C0201  page 175 : \1\ = P5E_CPU0_PE4_TX_C_DN<4> ; \2\ = P5E_CPU0_PE4_TX_DN<4>
PC1360  Q_CAP  0.1UF 25V 10% X7R  pkg 0402  page 287 : A = GND ; B = PVCCIN_CPU1_VREF

(kicad_pcb
	(version 20260206)
	(generator "pcbnew")
	(generator_version "10.0")
	(general
		(thickness 1.6)
		(legacy_teardrops no)
	)
	(paper "A4")
	(title_block
		(title "03242023_DA0F0TMBIJ0_F0T_Motherboard_J_brd_V01_OCP.brd")
		(comment 1 "Grand Teton / footprints 1089-1091 of 6105")
	)
	(layers
		(0 "F.Cu" signal "TOP")
		(4 "In1.Cu" signal "GND")
		(6 "In2.Cu" signal "IN1")
		(8 "In3.Cu" signal "GND1")
		(10 "In4.Cu" signal "IN2")
		(12 "In5.Cu" signal "GND2")
		(14 "In6.Cu" signal "IN3")
		(16 "In7.Cu" signal "GND3")
		(18 "In8.Cu" signal "VCC")
		(20 "In9.Cu" signal "VCC1")
		(22 "In10.Cu" signal "GND4")
		(24 "In11.Cu" signal "IN4")
		(26 "In12.Cu" signal "GND5")
		(28 "In13.Cu" signal "IN5")
		(30 "In14.Cu" signal "GND6")
		(32 "In15.Cu" signal "IN6")
		(34 "In16.Cu" signal "GND7")
		(2 "B.Cu" signal "BOTTOM")
		(9 "F.Adhes" user "F.Adhesive")
		(11 "B.Adhes" user "B.Adhesive")
		(13 "F.Paste" user "Package Geometry/Pastemask Top")
		(15 "B.Paste" user "Package Geometry/Pastemask Bottom")
		(5 "F.SilkS" user "Ref Des/Silkscreen Top")
		(7 "B.SilkS" user "Ref Des/Silkscreen Bottom")
		(1 "F.Mask" user "Board Geometry/Soldermask Top")
		(3 "B.Mask" user "Board Geometry/Soldermask Bottom")
		(17 "Dwgs.User" user "User.Drawings")
		(19 "Cmts.User" user "User.Comments")
		(21 "Eco1.User" user "User.Eco1")
		(23 "Eco2.User" user "User.Eco2")
		(25 "Edge.Cuts" user "Board Geometry/Outline")
		(27 "Margin" user)
		(31 "F.CrtYd" user "Package Geometry/Place Bound Top")
		(29 "B.CrtYd" user "Package Geometry/Place Bound Bottom")
		(35 "F.Fab" user "Ref Des/Assembly Top")
		(33 "B.Fab" user "Ref Des/Assembly Bottom")
	)
	(footprint ""
		(layer "F.Cu")
		(at 86.084918 -341.707978 -90)
		(property "Reference" "PC1360"
			(at 0 0 270)
			(layer "F.SilkS")
			(hide yes)
			(effects
				(font
					(size 1.27 1.27)
				)
			)
		)
		(property "Value" ""
			(at 0 0 270)
			(layer "F.Fab")
			(effects
				(font
					(size 1.27 1.27)
				)
			)
		)
		(duplicate_pad_numbers_are_jumpers no)
		(fp_line
			(start -0.7874 0.4064)
			(end -0.7874 -0.4064)
			(stroke
				(width 0.1524)
				(type default)
			)
			(layer "F.SilkS")
		)
		(fp_line
			(start 0.7874 0.4064)
			(end -0.7874 0.4064)
			(stroke
				(width 0.1524)
				(type default)
			)
			(layer "F.SilkS")
		)
		(fp_line
			(start -0.7874 -0.4064)
			(end 0.7874 -0.4064)
			(stroke
				(width 0.1524)
				(type default)
			)
			(layer "F.SilkS")
		)
		(fp_line
			(start 0.7874 -0.4064)
			(end 0.7874 0.4064)
			(stroke
				(width 0.1524)
				(type default)
			)
			(layer "F.SilkS")
		)
		(fp_line
			(start -0.67945 0.3048)
			(end -0.67945 -0.305054)
			(stroke
				(width 0.1)
				(type default)
			)
			(layer "F.Fab")
		)
		(fp_line
			(start -0.12065 0.3048)
			(end -0.67945 0.3048)
			(stroke
				(width 0.1)
				(type default)
			)
			(layer "F.Fab")
		)
		(fp_line
			(start 0.120396 0.3048)
			(end 0.120396 0.2794)
			(stroke
				(width 0.1)
				(type default)
			)
			(layer "F.Fab")
		)
		(fp_line
			(start 0.67945 0.3048)
			(end 0.120396 0.3048)
			(stroke
				(width 0.1)
				(type default)
			)
			(layer "F.Fab")
		)
		(fp_line
			(start -0.12065 0.2794)
			(end -0.12065 0.3048)
			(stroke
				(width 0.1)
				(type default)
			)
			(layer "F.Fab")
		)
		(fp_line
			(start 0.120396 0.2794)
			(end -0.12065 0.2794)
			(stroke
				(width 0.1)
				(type default)
			)
			(layer "F.Fab")
		)
		(fp_line
			(start -0.12065 -0.2794)
			(end 0.12065 -0.2794)
			(stroke
				(width 0.1)
				(type default)
			)
			(layer "F.Fab")
		)
		(fp_line
			(start 0.12065 -0.2794)
			(end 0.12065 -0.3048)
			(stroke
				(width 0.1)
				(type default)
			)
			(layer "F.Fab")
		)
		(fp_line
			(start 0.12065 -0.3048)
			(end 0.67945 -0.3048)
			(stroke
				(width 0.1)
				(type default)
			)
			(layer "F.Fab")
		)
		(fp_line
			(start 0.67945 -0.3048)
			(end 0.67945 0.3048)
			(stroke
				(width 0.1)
				(type default)
			)
			(layer "F.Fab")
		)
		(fp_line
			(start -0.67945 -0.305054)
			(end -0.12065 -0.305054)
			(stroke
				(width 0.1)
				(type default)
			)
			(layer "F.Fab")
		)
		(fp_line
			(start -0.12065 -0.305054)
			(end -0.12065 -0.2794)
			(stroke
				(width 0.1)
				(type default)
			)
			(layer "F.Fab")
		)
		(pad "1" smd circle
			(at -0.40005 0 270)
			(size 0 0)
			(layers "F.Cu" "F.Mask" "F.Paste")
			(net "GND")
		)
		(pad "2" smd circle
			(at 0.40005 0 270)
			(size 0 0)
			(layers "F.Cu" "F.Mask" "F.Paste")
			(net "PVCCIN_CPU1_VREF")
		)
	)
	(footprint ""
		(layer "F.Cu")
		(at 316.207648 -402.371052 -90)
		(property "Reference" "C1570"
			(at 0 0 270)
			(layer "F.SilkS")
			(hide yes)
			(effects
				(font
					(size 1.27 1.27)
				)
			)
		)
		(property "Value" ""
			(at 0 0 270)
			(layer "F.Fab")
			(effects
				(font
					(size 1.27 1.27)
				)
			)
		)
		(duplicate_pad_numbers_are_jumpers no)
		(fp_line
			(start -0.299974 0.150114)
			(end -0.299974 -0.150114)
			(stroke
				(width 0.1)
				(type default)
			)
			(layer "F.Fab")
		)
		(fp_line
			(start 0.299974 0.150114)
			(end -0.299974 0.150114)
			(stroke
				(width 0.1)
				(type default)
			)
			(layer "F.Fab")
		)
		(fp_line
			(start -0.299974 -0.150114)
			(end 0.299974 -0.150114)
			(stroke
				(width 0.1)
				(type default)
			)
			(layer "F.Fab")
		)
		(fp_line
			(start 0.299974 -0.150114)
			(end 0.299974 0.150114)
			(stroke
				(width 0.1)
				(type default)
			)
			(layer "F.Fab")
		)
		(pad "1" smd rect
			(at -0.2667 0 270)
			(size 0.3048 0.381)
			(layers "F.Cu" "F.Mask" "F.Paste")
			(net "P5E_CPU0_PE4_TX_C_DN<4>")
		)
		(pad "2" smd rect
			(at 0.2667 0 270)
			(size 0.3048 0.381)
			(layers "F.Cu" "F.Mask" "F.Paste")
			(net "P5E_CPU0_PE4_TX_DN<4>")
		)
	)
	(footprint ""
		(layer "F.Cu")
		(at 108.079286 -93.015562)
		(property "Reference" "Q81"
			(at -1.19126 1.843532 0)
			(unlocked yes)
			(layer "F.SilkS")
			(effects
				(font
					(size 0.7874 0.5842)
					(thickness 0.1524)
				)
				(justify left)
			)
		)
		(property "Value" ""
			(at 0 0 0)
			(layer "F.Fab")
			(effects
				(font
					(size 1.27 1.27)
				)
			)
		)
		(duplicate_pad_numbers_are_jumpers no)
		(fp_line
			(start -1.332738 -1.100074)
			(end -0.4826 -1.100074)
			(stroke
				(width 0.1524)
				(type default)
			)
			(layer "F.SilkS")
		)
		(fp_line
			(start -1.332738 1.100074)
			(end -1.332738 -1.100074)
			(stroke
				(width 0.1524)
				(type default)
			)
			(layer "F.SilkS")
		)
		(fp_line
			(start -0.4826 -1.100074)
			(end 0 -0.541274)
			(stroke
				(width 0.1524)
				(type default)
			)
			(layer "F.SilkS")
		)
		(fp_line
			(start 0 -0.541274)
			(end 0.4826 -1.100074)
			(stroke
				(width 0.1524)
				(type default)
			)
			(layer "F.SilkS")
		)
		(fp_line
			(start 0.4826 -1.100074)
			(end 1.332738 -1.100074)
			(stroke
				(width 0.1524)
				(type default)
			)
			(layer "F.SilkS")
		)
		(fp_line
			(start 1.332738 -1.100074)
			(end 1.332738 1.100074)
			(stroke
				(width 0.1524)
				(type default)
			)
			(layer "F.SilkS")
		)
		(fp_line
			(start 1.332738 1.100074)
			(end -1.332738 1.100074)
			(stroke
				(width 0.1524)
				(type default)
			)
			(layer "F.SilkS")
		)
		(fp_poly
			(pts
				(xy -0.649478 -1.9685) (xy -1.000506 -1.266444) (xy -1.351534 -1.9685)
			)
			(stroke
				(width 0)
				(type default)
			)
			(fill yes)
			(layer "F.SilkS")
		)
		(fp_line
			(start -0.674878 -1.100074)
			(end 0.674878 -1.100074)
			(stroke
				(width 0.1)
				(type default)
			)
			(layer "F.Fab")
		)
		(fp_line
			(start -0.674878 1.100074)
			(end -0.674878 -1.100074)
			(stroke
				(width 0.1)
				(type default)
			)
			(layer "F.Fab")
		)
		(fp_line
			(start 0.674878 -1.100074)
			(end 0.674878 1.100074)
			(stroke
				(width 0.1)
				(type default)
			)
			(layer "F.Fab")
		)
		(fp_line
			(start 0.674878 1.100074)
			(end -0.674878 1.100074)
			(stroke
				(width 0.1)
				(type default)
			)
			(layer "F.Fab")
		)
		(fp_poly
			(pts
				(xy -2.2352 -0.298958) (xy -2.2352 -1.001014) (xy -1.533144 -0.649986)
			)
			(stroke
				(width 0)
				(type default)
			)
			(fill yes)
			(layer "F.Fab")
		)
		(pad "1" smd rect
			(at -0.94996 -0.649986 90)
			(size 0.4318 0.508)
			(layers "F.Cu" "F.Mask" "F.Paste")
			(net "GND")
		)
		(pad "2" smd rect
			(at -0.94996 0 90)
			(size 0.4318 0.508)
			(layers "F.Cu" "F.Mask" "F.Paste")
			(net "PWRGD_PVCCINFAON_CPU0")
		)
		(pad "3" smd rect
			(at -0.94996 0.649986 90)
			(size 0.4318 0.508)
			(layers "F.Cu" "F.Mask" "F.Paste")
			(net "LED_PWRGD_PVNN_MAIN_CPU0_D")
		)
		(pad "4" smd rect
			(at 0.94996 0.649986 90)
			(size 0.4318 0.508)
			(layers "F.Cu" "F.Mask" "F.Paste")
			(net "GND")
		)
		(pad "5" smd rect
			(at 0.94996 0 90)
			(size 0.4318 0.508)
			(layers "F.Cu" "F.Mask" "F.Paste")
			(net "PWRGD_PVNN_MAIN_CPU0")
		)
		(pad "6" smd rect
			(at 0.94996 -0.649986 90)
			(size 0.4318 0.508)
			(layers "F.Cu" "F.Mask" "F.Paste")
			(net "LED_PWRGD_PVCCINFAON_CPU0_D")
		)
	)
)
